# TIMECARD (Time Appliance Project (Time Card)) — schematic netlist excerpt (pin names and nets, part order shuffled) for the footprints in the layout excerpt that follows; sources: Cadence DE-HDL packaged netlist, KiCad conversion of R4006-B0001-02_R01.brd

R136  RESISTOR  33OHM 1%  pkg SMC_0402R_H016  page 10 : \1\ = FT4232_FPGA_TMS ; \2\ = FPGA_TMS
C35  CAPACITOR  0.1UF 10%  pkg SMC_0402R_H022  page 9 : \1\ = C_CPU_RX_PCIE_MGT3_TXP ; \2\ = CPU_RX_PCIE_MGT3_TXP

(kicad_pcb
	(version 20260206)
	(generator "pcbnew")
	(generator_version "10.0")
	(general
		(thickness 1.6)
		(legacy_teardrops no)
	)
	(paper "A4")
	(title_block
		(title "timecard-production-celestica-r4006 — R4006-B0001-02_R01.brd")
		(comment 1 "Time Appliance Project (Time Card) / footprints 1013-1014 of 1113")
	)
	(layers
		(0 "F.Cu" signal "TOP")
		(4 "In1.Cu" signal "L02_GND1")
		(6 "In2.Cu" signal "L03_SIG1")
		(8 "In3.Cu" signal "L04_GND2")
		(10 "In4.Cu" signal "L05_VCC1")
		(12 "In5.Cu" signal "L06_VCC2")
		(14 "In6.Cu" signal "L07_GND3")
		(16 "In7.Cu" signal "L08_SIG2")
		(18 "In8.Cu" signal "L09_GND4")
		(2 "B.Cu" signal "BOTTOM")
		(9 "F.Adhes" user "F.Adhesive")
		(11 "B.Adhes" user "B.Adhesive")
		(13 "F.Paste" user "Package Geometry/Pastemask Top")
		(15 "B.Paste" user "Package Geometry/Pastemask Bottom")
		(5 "F.SilkS" user "Ref Des/Silkscreen Top")
		(7 "B.SilkS" user "Ref Des/Silkscreen Bottom")
		(1 "F.Mask" user "Board Geometry/Soldermask Top")
		(3 "B.Mask" user "Board Geometry/Soldermask Bottom")
		(17 "Dwgs.User" user "User.Drawings")
		(19 "Cmts.User" user "User.Comments")
		(21 "Eco1.User" user "User.Eco1")
		(23 "Eco2.User" user "User.Eco2")
		(25 "Edge.Cuts" user "Board Geometry/Outline")
		(27 "Margin" user)
		(31 "F.CrtYd" user "Package Geometry/Place Bound Top")
		(29 "B.CrtYd" user "Package Geometry/Place Bound Bottom")
		(35 "F.Fab" user "Ref Des/Assembly Top")
		(33 "B.Fab" user "Ref Des/Assembly Bottom")
	)
	(footprint ""
		(layer "B.Cu")
		(at 75.514962 -15.367 -90)
		(property "Reference" "C35"
			(at -1.778 -2.372868 270)
			(unlocked yes)
			(layer "B.SilkS")
			(effects
				(font
					(size 0.7874 0.5842)
					(thickness 0.1524)
				)
				(justify mirror)
			)
		)
		(property "Value" "VAL*"
			(at -0.0762 2.067306 270)
			(unlocked yes)
			(layer "B.Fab")
			(hide yes)
			(effects
				(font
					(size 0.7874 0.5842)
					(thickness 0.1524)
				)
				(justify mirror)
			)
		)
		(property "Tolerance" "TOL*"
			(at -0.0762 3.032506 270)
			(unlocked yes)
			(layer "Cmts.User")
			(hide yes)
			(effects
				(font
					(size 0.7874 0.5842)
					(thickness 0.1524)
				)
				(justify mirror)
			)
		)
		(property "User Part Number" "PARTNUM*"
			(at -0.1016 4.023106 270)
			(unlocked yes)
			(layer "Cmts.User")
			(hide yes)
			(effects
				(font
					(size 0.7874 0.5842)
					(thickness 0.1524)
				)
				(justify mirror)
			)
		)
		(property "Device Type" "CAPACITOR-G105-0B104-CK,0.1UF,A"
			(at -0.0508 1.127506 270)
			(unlocked yes)
			(layer "B.Fab")
			(hide yes)
			(effects
				(font
					(size 0.7874 0.5842)
					(thickness 0.1524)
				)
				(justify mirror)
			)
		)
		(duplicate_pad_numbers_are_jumpers no)
		(fp_line
			(start -1.143 0.5588)
			(end -1.143 -0.5588)
			(stroke
				(width 0.1)
				(type default)
			)
			(layer "B.SilkS")
		)
		(fp_line
			(start 1.143 0.5588)
			(end -1.143 0.5588)
			(stroke
				(width 0.1)
				(type default)
			)
			(layer "B.SilkS")
		)
		(fp_line
			(start -1.143 -0.5588)
			(end 1.143 -0.5588)
			(stroke
				(width 0.1)
				(type default)
			)
			(layer "B.SilkS")
		)
		(fp_line
			(start 1.143 -0.5588)
			(end 1.143 0.5588)
			(stroke
				(width 0.1)
				(type default)
			)
			(layer "B.SilkS")
		)
		(fp_rect
			(start 1.143 0.5588)
			(end -1.143 -0.5588)
			(stroke
				(width 0)
				(type default)
			)
			(fill no)
			(layer "B.CrtYd")
		)
		(fp_line
			(start -0.508 0.3048)
			(end -0.508 -0.3048)
			(stroke
				(width 0.1)
				(type default)
			)
			(layer "B.Fab")
		)
		(fp_line
			(start 0.508 0.3048)
			(end -0.508 0.3048)
			(stroke
				(width 0.1)
				(type default)
			)
			(layer "B.Fab")
		)
		(fp_line
			(start -0.508 -0.3048)
			(end 0.508 -0.3048)
			(stroke
				(width 0.1)
				(type default)
			)
			(layer "B.Fab")
		)
		(fp_line
			(start 0.508 -0.3048)
			(end 0.508 0.3048)
			(stroke
				(width 0.1)
				(type default)
			)
			(layer "B.Fab")
		)
		(pad "1" smd rect
			(at 0.5334 0 90)
			(size 0.7112 0.6096)
			(layers "B.Cu" "B.Mask" "B.Paste")
			(net "C_CPU_RX_PCIE_MGT3_TXP")
		)
		(pad "2" smd rect
			(at -0.5334 0 90)
			(size 0.7112 0.6096)
			(layers "B.Cu" "B.Mask" "B.Paste")
			(net "CPU_RX_PCIE_MGT3_TXP")
		)
		(zone
			(layer "B.Cu")
			(hatch none 0.5)
			(connect_pads
				(clearance 0)
			)
			(min_thickness 0.25)
			(keepout
				(tracks allowed)
				(vias not_allowed)
				(pads allowed)
				(copperpour not_allowed)
				(footprints allowed)
			)
			(placement
				(enabled no)
				(sheetname "")
			)
			(fill
				(thermal_gap 0.5)
				(thermal_bridge_width 0.5)
				(island_removal_mode 0)
			)
			(polygon
				(pts
					(xy 75.210162 -15.2908) (xy 75.819762 -15.2908) (xy 75.819762 -15.4432) (xy 75.210162 -15.4432)
				)
			)
		)
	)
	(footprint ""
		(layer "B.Cu")
		(at 140.2842 -74.2315)
		(property "Reference" "R136"
			(at 0.4318 -1.04013 0)
			(unlocked yes)
			(layer "B.SilkS")
			(effects
				(font
					(size 0.7874 0.5842)
					(thickness 0.1524)
				)
				(justify mirror)
			)
		)
		(property "Value" "VAL*"
			(at -0.02032 2.13233 0)
			(unlocked yes)
			(layer "B.Fab")
			(hide yes)
			(effects
				(font
					(size 0.7874 0.5842)
					(thickness 0.1524)
				)
				(justify mirror)
			)
		)
		(property "Tolerance" "TOL*"
			(at -0.044704 3.05435 0)
			(unlocked yes)
			(layer "Cmts.User")
			(hide yes)
			(effects
				(font
					(size 0.7874 0.5842)
					(thickness 0.1524)
				)
				(justify mirror)
			)
		)
		(property "User Part Number" "PARTNUM*"
			(at -0.02032 4.024884 0)
			(unlocked yes)
			(layer "Cmts.User")
			(hide yes)
			(effects
				(font
					(size 0.7874 0.5842)
					(thickness 0.1524)
				)
				(justify mirror)
			)
		)
		(property "Device Type" "RESISTOR-G155-133R0-01,33OHM,1%"
			(at -0.008382 1.210564 0)
			(unlocked yes)
			(layer "B.Fab")
			(hide yes)
			(effects
				(font
					(size 0.7874 0.5842)
					(thickness 0.1524)
				)
				(justify mirror)
			)
		)
		(duplicate_pad_numbers_are_jumpers no)
		(fp_line
			(start -1.143 -0.5588)
			(end 1.143 -0.5588)
			(stroke
				(width 0.1)
				(type default)
			)
			(layer "B.SilkS")
		)
		(fp_line
			(start -1.143 0.5588)
			(end -1.143 -0.5588)
			(stroke
				(width 0.1)
				(type default)
			)
			(layer "B.SilkS")
		)
		(fp_line
			(start 1.143 -0.5588)
			(end 1.143 0.5588)
			(stroke
				(width 0.1)
				(type default)
			)
			(layer "B.SilkS")
		)
		(fp_line
			(start 1.143 0.5588)
			(end -1.143 0.5588)
			(stroke
				(width 0.1)
				(type default)
			)
			(layer "B.SilkS")
		)
		(fp_rect
			(start -1.143 -0.5588)
			(end 1.143 0.5588)
			(stroke
				(width 0)
				(type default)
			)
			(fill no)
			(layer "B.CrtYd")
		)
		(fp_line
			(start -0.508 -0.3048)
			(end 0.508 -0.3048)
			(stroke
				(width 0.1)
				(type default)
			)
			(layer "B.Fab")
		)
		(fp_line
			(start -0.508 0.3048)
			(end -0.508 -0.3048)
			(stroke
				(width 0.1)
				(type default)
			)
			(layer "B.Fab")
		)
		(fp_line
			(start 0.508 -0.3048)
			(end 0.508 0.3048)
			(stroke
				(width 0.1)
				(type default)
			)
			(layer "B.Fab")
		)
		(fp_line
			(start 0.508 0.3048)
			(end -0.508 0.3048)
			(stroke
				(width 0.1)
				(type default)
			)
			(layer "B.Fab")
		)
		(pad "1" smd rect
			(at 0.5334 0 180)
			(size 0.7112 0.6096)
			(layers "B.Cu" "B.Mask" "B.Paste")
			(net "FT4232_FPGA_TMS")
		)
		(pad "2" smd rect
			(at -0.5334 0 180)
			(size 0.7112 0.6096)
			(layers "B.Cu" "B.Mask" "B.Paste")
			(net "FPGA_TMS")
		)
		(zone
			(layer "B.Cu")
			(hatch none 0.5)
			(connect_pads
				(clearance 0)
			)
			(min_thickness 0.25)
			(keepout
				(tracks allowed)
				(vias not_allowed)
				(pads allowed)
				(copperpour not_allowed)
				(footprints allowed)
			)
			(placement
				(enabled no)
				(sheetname "")
			)
			(fill
				(thermal_gap 0.5)
				(thermal_bridge_width 0.5)
				(island_removal_mode 0)
			)
			(polygon
				(pts
					(xy 140.208 -74.5363) (xy 140.208 -73.9267) (xy 140.3604 -73.9267) (xy 140.3604 -74.5363)
				)
			)
		)
	)
)
